(kicad_pcb
	(version 20260206)
	(generator "pcbnew")
	(generator_version "10.0")
	(general
		(thickness 1.6)
		(legacy_teardrops no)
	)
	(paper "A4")
	(title_block
		(title "timecard-production-celestica-r4006 — R4006-B0001-02_R01.brd")
		(comment 1 "Time Appliance Project (Time Card) / footprints 351-354 of 1113")
	)
	(layers
		(0 "F.Cu" signal "TOP")
		(4 "In1.Cu" signal "L02_GND1")
		(6 "In2.Cu" signal "L03_SIG1")
		(8 "In3.Cu" signal "L04_GND2")
		(10 "In4.Cu" signal "L05_VCC1")
		(12 "In5.Cu" signal "L06_VCC2")
		(14 "In6.Cu" signal "L07_GND3")
		(16 "In7.Cu" signal "L08_SIG2")
		(18 "In8.Cu" signal "L09_GND4")
		(2 "B.Cu" signal "BOTTOM")
		(9 "F.Adhes" user "F.Adhesive")
		(11 "B.Adhes" user "B.Adhesive")
		(13 "F.Paste" user "Package Geometry/Pastemask Top")
		(15 "B.Paste" user "Package Geometry/Pastemask Bottom")
		(5 "F.SilkS" user "Ref Des/Silkscreen Top")
		(7 "B.SilkS" user "Ref Des/Silkscreen Bottom")
		(1 "F.Mask" user "Board Geometry/Soldermask Top")
		(3 "B.Mask" user "Board Geometry/Soldermask Bottom")
		(17 "Dwgs.User" user "User.Drawings")
		(19 "Cmts.User" user "User.Comments")
		(21 "Eco1.User" user "User.Eco1")
		(23 "Eco2.User" user "User.Eco2")
		(25 "Edge.Cuts" user "Board Geometry/Outline")
		(27 "Margin" user)
		(31 "F.CrtYd" user "Package Geometry/Place Bound Top")
		(29 "B.CrtYd" user "Package Geometry/Place Bound Bottom")
		(35 "F.Fab" user "Ref Des/Assembly Top")
		(33 "B.Fab" user "Ref Des/Assembly Bottom")
	)
	(footprint ""
		(layer "F.Cu")
		(at 126.1364 -32.1056 180)
		(property "Reference" "C292"
			(at 0 -1.96977 0)
			(unlocked yes)
			(layer "F.SilkS")
			(effects
				(font
					(size 0.7874 0.5842)
					(thickness 0.1524)
				)
			)
		)
		(property "Value" "VAL*"
			(at 0.0762 3.134106 180)
			(unlocked yes)
			(layer "F.Fab")
			(hide yes)
			(effects
				(font
					(size 0.7874 0.5842)
					(thickness 0.1524)
				)
			)
		)
		(property "Tolerance" "TOL*"
			(at 0.0762 4.048506 180)
			(unlocked yes)
			(layer "Cmts.User")
			(hide yes)
			(effects
				(font
					(size 0.7874 0.5842)
					(thickness 0.1524)
				)
			)
		)
		(property "User Part Number" "PARTNUM*"
			(at 0.1016 5.013706 180)
			(unlocked yes)
			(layer "Cmts.User")
			(hide yes)
			(effects
				(font
					(size 0.7874 0.5842)
					(thickness 0.1524)
				)
			)
		)
		(property "Device Type" "CAPACITOR-G107-0F226-CM,22UF,2A"
			(at 0.0508 2.194306 180)
			(unlocked yes)
			(layer "F.Fab")
			(hide yes)
			(effects
				(font
					(size 0.7874 0.5842)
					(thickness 0.1524)
				)
			)
		)
		(duplicate_pad_numbers_are_jumpers no)
		(fp_line
			(start 1.5748 0.9398)
			(end 1.5748 -0.9398)
			(stroke
				(width 0.1)
				(type default)
			)
			(layer "F.SilkS")
		)
		(fp_line
			(start 1.5748 -0.9398)
			(end -1.5748 -0.9398)
			(stroke
				(width 0.1)
				(type default)
			)
			(layer "F.SilkS")
		)
		(fp_line
			(start -1.5748 0.9398)
			(end 1.5748 0.9398)
			(stroke
				(width 0.1)
				(type default)
			)
			(layer "F.SilkS")
		)
		(fp_line
			(start -1.5748 -0.9398)
			(end -1.5748 0.9398)
			(stroke
				(width 0.1)
				(type default)
			)
			(layer "F.SilkS")
		)
		(fp_rect
			(start 1.5748 0.9398)
			(end -1.5748 -0.9398)
			(stroke
				(width 0)
				(type default)
			)
			(fill no)
			(layer "F.CrtYd")
		)
		(fp_line
			(start 1.016 0.635)
			(end 1.016 -0.635)
			(stroke
				(width 0.1)
				(type default)
			)
			(layer "F.Fab")
		)
		(fp_line
			(start 1.016 -0.635)
			(end -1.016 -0.635)
			(stroke
				(width 0.1)
				(type default)
			)
			(layer "F.Fab")
		)
		(fp_line
			(start -1.016 0.635)
			(end 1.016 0.635)
			(stroke
				(width 0.1)
				(type default)
			)
			(layer "F.Fab")
		)
		(fp_line
			(start -1.016 -0.635)
			(end -1.016 0.635)
			(stroke
				(width 0.1)
				(type default)
			)
			(layer "F.Fab")
		)
		(pad "1" smd rect
			(at -0.8382 0 180)
			(size 0.9652 1.3716)
			(layers "F.Cu" "F.Mask" "F.Paste")
			(net "XP2R5V_FPGA")
		)
		(pad "2" smd rect
			(at 0.8382 0 180)
			(size 0.9652 1.3716)
			(layers "F.Cu" "F.Mask" "F.Paste")
			(net "SG")
		)
		(zone
			(layer "F.Cu")
			(hatch none 0.5)
			(connect_pads
				(clearance 0)
			)
			(min_thickness 0.25)
			(keepout
				(tracks not_allowed)
				(vias allowed)
				(pads allowed)
				(copperpour not_allowed)
				(footprints allowed)
			)
			(placement
				(enabled no)
				(sheetname "")
			)
			(fill
				(thermal_gap 0.5)
				(thermal_bridge_width 0.5)
				(island_removal_mode 0)
			)
			(polygon
				(pts
					(xy 125.9078 -32.7406) (xy 125.9078 -31.4706) (xy 126.365 -31.4706) (xy 126.365 -32.7406)
				)
			)
		)
		(zone
			(layer "F.Cu")
			(hatch none 0.5)
			(connect_pads
				(clearance 0)
			)
			(min_thickness 0.25)
			(keepout
				(tracks allowed)
				(vias not_allowed)
				(pads allowed)
				(copperpour not_allowed)
				(footprints allowed)
			)
			(placement
				(enabled no)
				(sheetname "")
			)
			(fill
				(thermal_gap 0.5)
				(thermal_bridge_width 0.5)
				(island_removal_mode 0)
			)
			(polygon
				(pts
					(xy 125.9078 -32.7406) (xy 125.9078 -31.4706) (xy 126.365 -31.4706) (xy 126.365 -32.7406)
				)
			)
		)
	)
	(footprint ""
		(layer "F.Cu")
		(at 15.3924 -42.37863 -90)
		(property "Reference" "C84"
			(at 2.11963 -0.64135 90)
			(unlocked yes)
			(layer "F.SilkS")
			(effects
				(font
					(size 0.635 0.4064)
					(thickness 0.1524)
				)
			)
		)
		(property "Value" "VAL*"
			(at 0.0762 2.067306 270)
			(unlocked yes)
			(layer "F.Fab")
			(hide yes)
			(effects
				(font
					(size 0.7874 0.5842)
					(thickness 0.1524)
				)
			)
		)
		(property "Tolerance" "TOL*"
			(at 0.0762 3.032506 270)
			(unlocked yes)
			(layer "Cmts.User")
			(hide yes)
			(effects
				(font
					(size 0.7874 0.5842)
					(thickness 0.1524)
				)
			)
		)
		(property "User Part Number" "PARTNUM*"
			(at 0.1016 4.023106 270)
			(unlocked yes)
			(layer "Cmts.User")
			(hide yes)
			(effects
				(font
					(size 0.7874 0.5842)
					(thickness 0.1524)
				)
			)
		)
		(property "Device Type" "CAPACITOR-G105-0B104-CK,0.1UF,A"
			(at 0.0508 1.127506 270)
			(unlocked yes)
			(layer "F.Fab")
			(hide yes)
			(effects
				(font
					(size 0.7874 0.5842)
					(thickness 0.1524)
				)
			)
		)
		(duplicate_pad_numbers_are_jumpers no)
		(fp_line
			(start -1.143 0.5588)
			(end 1.143 0.5588)
			(stroke
				(width 0.1)
				(type default)
			)
			(layer "F.SilkS")
		)
		(fp_line
			(start 1.143 0.5588)
			(end 1.143 -0.5588)
			(stroke
				(width 0.1)
				(type default)
			)
			(layer "F.SilkS")
		)
		(fp_line
			(start -1.143 -0.5588)
			(end -1.143 0.5588)
			(stroke
				(width 0.1)
				(type default)
			)
			(layer "F.SilkS")
		)
		(fp_line
			(start 1.143 -0.5588)
			(end -1.143 -0.5588)
			(stroke
				(width 0.1)
				(type default)
			)
			(layer "F.SilkS")
		)
		(fp_rect
			(start 1.143 0.5588)
			(end -1.143 -0.5588)
			(stroke
				(width 0)
				(type default)
			)
			(fill no)
			(layer "F.CrtYd")
		)
		(fp_line
			(start -0.508 0.3048)
			(end 0.508 0.3048)
			(stroke
				(width 0.1)
				(type default)
			)
			(layer "F.Fab")
		)
		(fp_line
			(start 0.508 0.3048)
			(end 0.508 -0.3048)
			(stroke
				(width 0.1)
				(type default)
			)
			(layer "F.Fab")
		)
		(fp_line
			(start -0.508 -0.3048)
			(end -0.508 0.3048)
			(stroke
				(width 0.1)
				(type default)
			)
			(layer "F.Fab")
		)
		(fp_line
			(start 0.508 -0.3048)
			(end -0.508 -0.3048)
			(stroke
				(width 0.1)
				(type default)
			)
			(layer "F.Fab")
		)
		(pad "1" smd rect
			(at -0.5334 0 270)
			(size 0.7112 0.6096)
			(layers "F.Cu" "F.Mask" "F.Paste")
			(net "XP3R3V_FPGA")
		)
		(pad "2" smd rect
			(at 0.5334 0 270)
			(size 0.7112 0.6096)
			(layers "F.Cu" "F.Mask" "F.Paste")
			(net "SG")
		)
		(zone
			(layer "F.Cu")
			(hatch none 0.5)
			(connect_pads
				(clearance 0)
			)
			(min_thickness 0.25)
			(keepout
				(tracks allowed)
				(vias not_allowed)
				(pads allowed)
				(copperpour not_allowed)
				(footprints allowed)
			)
			(placement
				(enabled no)
				(sheetname "")
			)
			(fill
				(thermal_gap 0.5)
				(thermal_bridge_width 0.5)
				(island_removal_mode 0)
			)
			(polygon
				(pts
					(xy 15.0876 -42.30243) (xy 15.6972 -42.30243) (xy 15.6972 -42.45483) (xy 15.0876 -42.45483)
				)
			)
		)
	)
	(footprint ""
		(layer "F.Cu")
		(at 1.500124 -68.09994 90)
		(property "Reference" "DS16"
			(at 4.16306 1.587246 90)
			(unlocked yes)
			(layer "F.SilkS")
			(effects
				(font
					(size 0.7874 0.5842)
					(thickness 0.1524)
				)
			)
		)
		(property "Value" ""
			(at 0 0 90)
			(layer "F.Fab")
			(effects
				(font
					(size 1.27 1.27)
				)
			)
		)
		(property "User Part Number" "PARTNUM*"
			(at 0.015494 4.486402 90)
			(unlocked yes)
			(layer "Cmts.User")
			(hide yes)
			(effects
				(font
					(size 0.7874 0.5842)
					(thickness 0.1524)
				)
			)
		)
		(property "Device Type" "LED_4P_V14-G170-10189-01"
			(at 0.015494 3.292602 90)
			(unlocked yes)
			(layer "F.Fab")
			(hide yes)
			(effects
				(font
					(size 0.7874 0.5842)
					(thickness 0.1524)
				)
			)
		)
		(duplicate_pad_numbers_are_jumpers no)
		(fp_line
			(start 1.378966 -0.829056)
			(end -1.378966 -0.829056)
			(stroke
				(width 0.1)
				(type default)
			)
			(layer "F.SilkS")
		)
		(fp_line
			(start -1.378966 -0.829056)
			(end -1.378966 -0.452628)
			(stroke
				(width 0.1)
				(type default)
			)
			(layer "F.SilkS")
		)
		(fp_line
			(start 1.998218 -0.452628)
			(end 1.378966 -0.452628)
			(stroke
				(width 0.1)
				(type default)
			)
			(layer "F.SilkS")
		)
		(fp_line
			(start 1.378966 -0.452628)
			(end 1.378966 -0.829056)
			(stroke
				(width 0.1)
				(type default)
			)
			(layer "F.SilkS")
		)
		(fp_line
			(start -1.378966 -0.452628)
			(end -1.998218 -0.452628)
			(stroke
				(width 0.1)
				(type default)
			)
			(layer "F.SilkS")
		)
		(fp_line
			(start -1.998218 -0.452628)
			(end -1.998218 1.103884)
			(stroke
				(width 0.1)
				(type default)
			)
			(layer "F.SilkS")
		)
		(fp_line
			(start 1.998218 1.103884)
			(end 1.998218 -0.452628)
			(stroke
				(width 0.1)
				(type default)
			)
			(layer "F.SilkS")
		)
		(fp_line
			(start -1.998218 1.103884)
			(end 1.998218 1.103884)
			(stroke
				(width 0.1)
				(type default)
			)
			(layer "F.SilkS")
		)
		(fp_poly
			(pts
				(xy 0.918464 -1.698498) (xy 1.223264 -1.46939) (xy 0.994664 -1.46939) (xy 0.994664 -1.24079) (xy 0.842264 -1.24079)
				(xy 0.842264 -1.46939) (xy 0.613664 -1.46939)
			)
			(stroke
				(width 0)
				(type default)
			)
			(fill yes)
			(layer "F.SilkS")
		)
		(fp_poly
			(pts
				(xy -0.73406 -1.677416) (xy -0.42926 -1.448308) (xy -0.65786 -1.448308) (xy -0.65786 -1.219708)
				(xy -0.81026 -1.219708) (xy -0.81026 -1.448308) (xy -1.03886 -1.448308)
			)
			(stroke
				(width 0)
				(type default)
			)
			(fill yes)
			(layer "F.SilkS")
		)
		(fp_poly
			(pts
				(xy -2.252218 1.357884) (xy -2.252218 -0.706628) (xy -1.632966 -0.706628) (xy -1.632966 -1.083056)
				(xy 1.632966 -1.083056) (xy 1.632966 -0.706628) (xy 2.252218 -0.706628) (xy 2.252218 1.357884)
			)
			(stroke
				(width 0)
				(type default)
			)
			(fill no)
			(layer "F.CrtYd")
		)
		(fp_line
			(start 1.124966 -0.575056)
			(end -1.124966 -0.575056)
			(stroke
				(width 0.1)
				(type default)
			)
			(layer "F.Fab")
		)
		(fp_line
			(start -1.124966 -0.575056)
			(end -1.124966 -0.075184)
			(stroke
				(width 0.1)
				(type default)
			)
			(layer "F.Fab")
		)
		(fp_line
			(start 1.325118 -0.075184)
			(end 1.124966 -0.075184)
			(stroke
				(width 0.1)
				(type default)
			)
			(layer "F.Fab")
		)
		(fp_line
			(start 1.124966 -0.075184)
			(end 1.124966 -0.575056)
			(stroke
				(width 0.1)
				(type default)
			)
			(layer "F.Fab")
		)
		(fp_line
			(start -1.124966 -0.075184)
			(end -1.325118 -0.075184)
			(stroke
				(width 0.1)
				(type default)
			)
			(layer "F.Fab")
		)
		(fp_line
			(start -1.325118 -0.075184)
			(end -1.325118 0.574802)
			(stroke
				(width 0.1)
				(type default)
			)
			(layer "F.Fab")
		)
		(fp_line
			(start 1.325118 0.574802)
			(end 1.325118 -0.075184)
			(stroke
				(width 0.1)
				(type default)
			)
			(layer "F.Fab")
		)
		(fp_line
			(start -1.325118 0.574802)
			(end 1.325118 0.574802)
			(stroke
				(width 0.1)
				(type default)
			)
			(layer "F.Fab")
		)
		(fp_poly
			(pts
				(xy 0.918464 -1.698498) (xy 1.223264 -1.46939) (xy 0.994664 -1.46939) (xy 0.994664 -1.24079) (xy 0.842264 -1.24079)
				(xy 0.842264 -1.46939) (xy 0.613664 -1.46939)
			)
			(stroke
				(width 0)
				(type default)
			)
			(fill yes)
			(layer "F.Fab")
		)
		(fp_poly
			(pts
				(xy -0.73406 -1.677416) (xy -0.42926 -1.448308) (xy -0.65786 -1.448308) (xy -0.65786 -1.219708)
				(xy -0.81026 -1.219708) (xy -0.81026 -1.448308) (xy -1.03886 -1.448308)
			)
			(stroke
				(width 0)
				(type default)
			)
			(fill yes)
			(layer "F.Fab")
		)
		(fp_text user "1"
			(at -2.37617 0.376936 90)
			(unlocked yes)
			(layer "F.SilkS")
			(effects
				(font
					(size 0.7874 0.5842)
					(thickness 0.1524)
				)
			)
		)
		(fp_text user "3"
			(at 0.69469 2.055876 0)
			(unlocked yes)
			(layer "F.SilkS")
			(effects
				(font
					(size 0.7874 0.5842)
					(thickness 0.1524)
				)
			)
		)
		(fp_text user "2"
			(at -0.44831 2.182876 0)
			(unlocked yes)
			(layer "F.SilkS")
			(effects
				(font
					(size 0.7874 0.5842)
					(thickness 0.1524)
				)
			)
		)
		(fp_text user "4"
			(at 1.77038 1.166876 0)
			(unlocked yes)
			(layer "F.Fab")
			(effects
				(font
					(size 0.7874 0.5842)
					(thickness 0.1524)
				)
			)
		)
		(fp_text user "3"
			(at 0.75438 1.166876 0)
			(unlocked yes)
			(layer "F.Fab")
			(effects
				(font
					(size 0.7874 0.5842)
					(thickness 0.1524)
				)
			)
		)
		(fp_text user "2"
			(at -0.38862 1.166876 0)
			(unlocked yes)
			(layer "F.Fab")
			(effects
				(font
					(size 0.7874 0.5842)
					(thickness 0.1524)
				)
			)
		)
		(fp_text user "1"
			(at -1.46431 1.293876 0)
			(unlocked yes)
			(layer "F.Fab")
			(effects
				(font
					(size 0.7874 0.5842)
					(thickness 0.1524)
				)
			)
		)
		(pad "1" smd rect
			(at -1.325118 0.245872 90)
			(size 0.8382 0.889)
			(layers "F.Cu" "F.Mask" "F.Paste")
			(net "UNNAMED_14_LED4PV14_I267_1")
		)
		(pad "2" smd rect
			(at -0.424942 0.595884 90)
			(size 0.4572 0.508)
			(layers "F.Cu" "F.Mask" "F.Paste")
			(net "XP3R3V_FPGA")
		)
		(pad "3" smd rect
			(at 0.424942 0.595884 90)
			(size 0.4572 0.508)
			(layers "F.Cu" "F.Mask" "F.Paste")
			(net "UNNAMED_14_LED4PV14_I267_3")
		)
		(pad "4" smd rect
			(at 1.325118 0.245872 90)
			(size 0.8382 0.889)
			(layers "F.Cu" "F.Mask" "F.Paste")
			(net "UNNAMED_14_LED4PV14_I267_4")
		)
	)
	(footprint ""
		(layer "F.Cu")
		(at 90.678 -59.9186 90)
		(property "Reference" "Y1"
			(at 2.4384 0.16637 90)
			(unlocked yes)
			(layer "F.SilkS")
			(effects
				(font
					(size 0.7874 0.5842)
					(thickness 0.1524)
				)
			)
		)
		(property "Value" "VAL*"
			(at -0.038862 5.168646 90)
			(unlocked yes)
			(layer "F.Fab")
			(hide yes)
			(effects
				(font
					(size 0.7874 0.5842)
					(thickness 0.1524)
				)
			)
		)
		(property "User Part Number" "PARTNUM*"
			(at 0 3.255264 90)
			(unlocked yes)
			(layer "Cmts.User")
			(hide yes)
			(effects
				(font
					(size 0.7874 0.5842)
					(thickness 0.1524)
				)
			)
		)
		(property "Device Type" "XTAL_2-G131-10075-01"
			(at 0 2.061464 90)
			(unlocked yes)
			(layer "F.Fab")
			(hide yes)
			(effects
				(font
					(size 0.7874 0.5842)
					(thickness 0.1524)
				)
			)
		)
		(property "Tolerance" "TOL*"
			(at -0.017272 4.188714 90)
			(unlocked yes)
			(layer "Cmts.User")
			(hide yes)
			(effects
				(font
					(size 0.7874 0.5842)
					(thickness 0.1524)
				)
			)
		)
		(duplicate_pad_numbers_are_jumpers no)
		(fp_line
			(start 1.347978 -0.9525)
			(end 1.347978 0.9525)
			(stroke
				(width 0.1)
				(type default)
			)
			(layer "F.SilkS")
		)
		(fp_line
			(start -1.347978 -0.9525)
			(end 1.347978 -0.9525)
			(stroke
				(width 0.1)
				(type default)
			)
			(layer "F.SilkS")
		)
		(fp_line
			(start 1.347978 0.9525)
			(end -1.347978 0.9525)
			(stroke
				(width 0.1)
				(type default)
			)
			(layer "F.SilkS")
		)
		(fp_line
			(start -1.347978 0.9525)
			(end -1.347978 -0.9525)
			(stroke
				(width 0.1)
				(type default)
			)
			(layer "F.SilkS")
		)
		(fp_rect
			(start -1.601978 -1.2065)
			(end 1.601978 1.2065)
			(stroke
				(width 0)
				(type default)
			)
			(fill no)
			(layer "F.CrtYd")
		)
		(fp_line
			(start 1.050036 -0.649986)
			(end 1.050036 0.649986)
			(stroke
				(width 0.1)
				(type default)
			)
			(layer "F.Fab")
		)
		(fp_line
			(start -1.050036 -0.649986)
			(end 1.050036 -0.649986)
			(stroke
				(width 0.1)
				(type default)
			)
			(layer "F.Fab")
		)
		(fp_line
			(start 1.050036 0.649986)
			(end -1.050036 0.649986)
			(stroke
				(width 0.1)
				(type default)
			)
			(layer "F.Fab")
		)
		(fp_line
			(start -1.050036 0.649986)
			(end -1.050036 -0.649986)
			(stroke
				(width 0.1)
				(type default)
			)
			(layer "F.Fab")
		)
		(pad "1" smd rect
			(at -0.674878 0 90)
			(size 0.8382 1.397)
			(layers "F.Cu" "F.Mask" "F.Paste")
			(net "UNNAMED_9_BNO080LGA28_I29_XOUT3")
		)
		(pad "2" smd rect
			(at 0.674878 0 90)
			(size 0.8382 1.397)
			(layers "F.Cu" "F.Mask" "F.Paste")
			(net "UNNAMED_9_CAPACITOR_I17_1")
		)
		(zone
			(layer "F.Cu")
			(hatch none 0.5)
			(connect_pads
				(clearance 0)
			)
			(min_thickness 0.25)
			(keepout
				(tracks allowed)
				(vias not_allowed)
				(pads allowed)
				(copperpour not_allowed)
				(footprints allowed)
			)
			(placement
				(enabled no)
				(sheetname "")
			)
			(fill
				(thermal_gap 0.5)
				(thermal_bridge_width 0.5)
				(island_removal_mode 0)
			)
			(polygon
				(pts
					(xy 90.028014 -59.662822) (xy 91.327986 -59.662822) (xy 91.327986 -60.174378) (xy 90.028014 -60.174378)
				)
			)
		)
	)
)
